(kicad_pcb
	(version 20260206)
	(generator "pcbnew")
	(generator_version "10.0")
	(general
		(thickness 1.6)
		(legacy_teardrops no)
	)
	(paper "A4")
	(title_block
		(title "timecard-production-celestica-r4006 — R4006-B0001-02_R01.brd")
		(comment 1 "Time Appliance Project (Time Card) / footprints 428-433 of 1113")
	)
	(layers
		(0 "F.Cu" signal "TOP")
		(4 "In1.Cu" signal "L02_GND1")
		(6 "In2.Cu" signal "L03_SIG1")
		(8 "In3.Cu" signal "L04_GND2")
		(10 "In4.Cu" signal "L05_VCC1")
		(12 "In5.Cu" signal "L06_VCC2")
		(14 "In6.Cu" signal "L07_GND3")
		(16 "In7.Cu" signal "L08_SIG2")
		(18 "In8.Cu" signal "L09_GND4")
		(2 "B.Cu" signal "BOTTOM")
		(9 "F.Adhes" user "F.Adhesive")
		(11 "B.Adhes" user "B.Adhesive")
		(13 "F.Paste" user "Package Geometry/Pastemask Top")
		(15 "B.Paste" user "Package Geometry/Pastemask Bottom")
		(5 "F.SilkS" user "Ref Des/Silkscreen Top")
		(7 "B.SilkS" user "Ref Des/Silkscreen Bottom")
		(1 "F.Mask" user "Board Geometry/Soldermask Top")
		(3 "B.Mask" user "Board Geometry/Soldermask Bottom")
		(17 "Dwgs.User" user "User.Drawings")
		(19 "Cmts.User" user "User.Comments")
		(21 "Eco1.User" user "User.Eco1")
		(23 "Eco2.User" user "User.Eco2")
		(25 "Edge.Cuts" user "Board Geometry/Outline")
		(27 "Margin" user)
		(31 "F.CrtYd" user "Package Geometry/Place Bound Top")
		(29 "B.CrtYd" user "Package Geometry/Place Bound Bottom")
		(35 "F.Fab" user "Ref Des/Assembly Top")
		(33 "B.Fab" user "Ref Des/Assembly Bottom")
	)
	(footprint ""
		(layer "F.Cu")
		(at 89.8652 -100.2538)
		(property "Reference" "C55"
			(at 1.905 0.16637 0)
			(unlocked yes)
			(layer "F.SilkS")
			(effects
				(font
					(size 0.7874 0.5842)
					(thickness 0.1524)
				)
			)
		)
		(property "Value" "VAL*"
			(at 0.193548 2.13614 0)
			(unlocked yes)
			(layer "F.Fab")
			(hide yes)
			(effects
				(font
					(size 0.7874 0.5842)
					(thickness 0.1524)
				)
			)
		)
		(property "User Part Number" "PARTNUM*"
			(at 0.216154 4.185666 0)
			(unlocked yes)
			(layer "Cmts.User")
			(hide yes)
			(effects
				(font
					(size 0.7874 0.5842)
					(thickness 0.1524)
				)
			)
		)
		(property "Device Type" "CAPACITOR-G104-0A180-FJ,18PF,5%"
			(at 0.184404 1.180592 0)
			(unlocked yes)
			(layer "F.Fab")
			(hide yes)
			(effects
				(font
					(size 0.7874 0.5842)
					(thickness 0.1524)
				)
			)
		)
		(property "Tolerance" "TOL*"
			(at 0.216154 3.1496 0)
			(unlocked yes)
			(layer "Cmts.User")
			(hide yes)
			(effects
				(font
					(size 0.7874 0.5842)
					(thickness 0.1524)
				)
			)
		)
		(duplicate_pad_numbers_are_jumpers no)
		(fp_line
			(start -0.671322 -0.4445)
			(end 0.671322 -0.4445)
			(stroke
				(width 0.1)
				(type default)
			)
			(layer "F.SilkS")
		)
		(fp_line
			(start -0.671322 0.4445)
			(end -0.671322 -0.4445)
			(stroke
				(width 0.1)
				(type default)
			)
			(layer "F.SilkS")
		)
		(fp_line
			(start 0.671322 -0.4445)
			(end 0.671322 0.4445)
			(stroke
				(width 0.1)
				(type default)
			)
			(layer "F.SilkS")
		)
		(fp_line
			(start 0.671322 0.4445)
			(end -0.671322 0.4445)
			(stroke
				(width 0.1)
				(type default)
			)
			(layer "F.SilkS")
		)
		(fp_rect
			(start -0.671322 0.4445)
			(end 0.671322 -0.4445)
			(stroke
				(width 0)
				(type default)
			)
			(fill no)
			(layer "F.CrtYd")
		)
		(fp_line
			(start -0.31496 -0.1651)
			(end -0.31496 0.1651)
			(stroke
				(width 0.1)
				(type default)
			)
			(layer "F.Fab")
		)
		(fp_line
			(start -0.31496 0.1651)
			(end 0.31496 0.1651)
			(stroke
				(width 0.1)
				(type default)
			)
			(layer "F.Fab")
		)
		(fp_line
			(start 0.31496 -0.1651)
			(end -0.31496 -0.1651)
			(stroke
				(width 0.1)
				(type default)
			)
			(layer "F.Fab")
		)
		(fp_line
			(start 0.31496 0.1651)
			(end 0.31496 -0.1651)
			(stroke
				(width 0.1)
				(type default)
			)
			(layer "F.Fab")
		)
		(pad "1" smd rect
			(at -0.264922 0)
			(size 0.3048 0.381)
			(layers "F.Cu" "F.Mask" "F.Paste")
			(net "XP3R3V_COMP")
		)
		(pad "2" smd rect
			(at 0.264922 0)
			(size 0.3048 0.381)
			(layers "F.Cu" "F.Mask" "F.Paste")
			(net "XP3R3V_AGND")
		)
		(zone
			(layer "F.Cu")
			(hatch none 0.5)
			(connect_pads
				(clearance 0)
			)
			(min_thickness 0.25)
			(keepout
				(tracks allowed)
				(vias not_allowed)
				(pads allowed)
				(copperpour not_allowed)
				(footprints allowed)
			)
			(placement
				(enabled no)
				(sheetname "")
			)
			(fill
				(thermal_gap 0.5)
				(thermal_bridge_width 0.5)
				(island_removal_mode 0)
			)
			(polygon
				(pts
					(xy 89.752678 -100.0633) (xy 89.977722 -100.0633) (xy 89.977722 -100.4443) (xy 89.752678 -100.4443)
				)
			)
		)
	)
	(footprint ""
		(layer "F.Cu")
		(at 125.349 -89.535 90)
		(property "Reference" "R268"
			(at -3.429 0.03937 90)
			(unlocked yes)
			(layer "F.SilkS")
			(effects
				(font
					(size 0.7874 0.5842)
					(thickness 0.1524)
				)
			)
		)
		(property "Value" "VAL*"
			(at 0.02032 2.13233 90)
			(unlocked yes)
			(layer "F.Fab")
			(hide yes)
			(effects
				(font
					(size 0.7874 0.5842)
					(thickness 0.1524)
				)
			)
		)
		(property "Device Type" "RESISTOR-G155-11003-01,100KOHMA"
			(at 0.008382 1.210564 90)
			(unlocked yes)
			(layer "F.Fab")
			(hide yes)
			(effects
				(font
					(size 0.7874 0.5842)
					(thickness 0.1524)
				)
			)
		)
		(property "User Part Number" "PARTNUM*"
			(at 0.02032 4.024884 90)
			(unlocked yes)
			(layer "Cmts.User")
			(hide yes)
			(effects
				(font
					(size 0.7874 0.5842)
					(thickness 0.1524)
				)
			)
		)
		(property "Tolerance" "TOL*"
			(at 0.044704 3.05435 90)
			(unlocked yes)
			(layer "Cmts.User")
			(hide yes)
			(effects
				(font
					(size 0.7874 0.5842)
					(thickness 0.1524)
				)
			)
		)
		(duplicate_pad_numbers_are_jumpers no)
		(fp_line
			(start 1.143 -0.5588)
			(end -1.143 -0.5588)
			(stroke
				(width 0.1)
				(type default)
			)
			(layer "F.SilkS")
		)
		(fp_line
			(start -1.143 -0.5588)
			(end -1.143 0.5588)
			(stroke
				(width 0.1)
				(type default)
			)
			(layer "F.SilkS")
		)
		(fp_line
			(start 1.143 0.5588)
			(end 1.143 -0.5588)
			(stroke
				(width 0.1)
				(type default)
			)
			(layer "F.SilkS")
		)
		(fp_line
			(start -1.143 0.5588)
			(end 1.143 0.5588)
			(stroke
				(width 0.1)
				(type default)
			)
			(layer "F.SilkS")
		)
		(fp_rect
			(start 1.143 -0.5588)
			(end -1.143 0.5588)
			(stroke
				(width 0)
				(type default)
			)
			(fill no)
			(layer "F.CrtYd")
		)
		(fp_line
			(start 0.508 -0.3048)
			(end -0.508 -0.3048)
			(stroke
				(width 0.1)
				(type default)
			)
			(layer "F.Fab")
		)
		(fp_line
			(start -0.508 -0.3048)
			(end -0.508 0.3048)
			(stroke
				(width 0.1)
				(type default)
			)
			(layer "F.Fab")
		)
		(fp_line
			(start 0.508 0.3048)
			(end 0.508 -0.3048)
			(stroke
				(width 0.1)
				(type default)
			)
			(layer "F.Fab")
		)
		(fp_line
			(start -0.508 0.3048)
			(end 0.508 0.3048)
			(stroke
				(width 0.1)
				(type default)
			)
			(layer "F.Fab")
		)
		(pad "1" smd rect
			(at -0.5334 0 90)
			(size 0.7112 0.6096)
			(layers "F.Cu" "F.Mask" "F.Paste")
			(net "XP3R3V_FPGA")
		)
		(pad "2" smd rect
			(at 0.5334 0 90)
			(size 0.7112 0.6096)
			(layers "F.Cu" "F.Mask" "F.Paste")
			(net "GPS_UART_RXD")
		)
		(zone
			(layer "F.Cu")
			(hatch none 0.5)
			(connect_pads
				(clearance 0)
			)
			(min_thickness 0.25)
			(keepout
				(tracks allowed)
				(vias not_allowed)
				(pads allowed)
				(copperpour not_allowed)
				(footprints allowed)
			)
			(placement
				(enabled no)
				(sheetname "")
			)
			(fill
				(thermal_gap 0.5)
				(thermal_bridge_width 0.5)
				(island_removal_mode 0)
			)
			(polygon
				(pts
					(xy 125.0442 -89.6112) (xy 125.0442 -89.4588) (xy 125.6538 -89.4588) (xy 125.6538 -89.6112)
				)
			)
		)
		(zone
			(layer "F.Cu")
			(hatch none 0.5)
			(connect_pads
				(clearance 0)
			)
			(min_thickness 0.25)
			(keepout
				(tracks not_allowed)
				(vias allowed)
				(pads allowed)
				(copperpour not_allowed)
				(footprints allowed)
			)
			(placement
				(enabled no)
				(sheetname "")
			)
			(fill
				(thermal_gap 0.5)
				(thermal_bridge_width 0.5)
				(island_removal_mode 0)
			)
			(polygon
				(pts
					(xy 125.0442 -89.6112) (xy 125.0442 -89.4588) (xy 125.6538 -89.4588) (xy 125.6538 -89.6112)
				)
			)
		)
	)
	(footprint ""
		(layer "F.Cu")
		(at 19.812 -83.947)
		(property "Reference" "TP5"
			(at 0 0 0)
			(layer "F.SilkS")
			(hide yes)
			(effects
				(font
					(size 1.27 1.27)
				)
			)
		)
		(property "Value" ""
			(at 0 0 0)
			(layer "F.Fab")
			(effects
				(font
					(size 1.27 1.27)
				)
			)
		)
		(property "Device Type" "TP_PIONT-TP010CT020B030_PTH-TPA"
			(at -1.341882 0.996696 0)
			(unlocked yes)
			(layer "F.Fab")
			(hide yes)
			(effects
				(font
					(size 0.7874 0.5842)
					(thickness 0.1524)
				)
				(justify left)
			)
		)
		(duplicate_pad_numbers_are_jumpers no)
		(fp_poly
			(pts
				(arc
					(start 0.889 0)
					(mid -0.889 0)
					(end 0.889 0)
				)
			)
			(stroke
				(width 0)
				(type default)
			)
			(fill no)
			(layer "B.CrtYd")
		)
		(fp_poly
			(pts
				(arc
					(start 0.889 0)
					(mid -0.889 0)
					(end 0.889 0)
				)
			)
			(stroke
				(width 0)
				(type default)
			)
			(fill no)
			(layer "F.CrtYd")
		)
		(pad "1" thru_hole circle
			(at 0 0)
			(size 0.508 0.508)
			(drill 0.254)
			(layers "*.Cu" "*.Mask")
			(remove_unused_layers no)
			(net "UNNAMED_524_FT4232HLREELQFP64_I")
			(clearance 0.1016)
			(padstack
				(mode front_inner_back)
				(layer "Inner"
					(shape circle)
					(size 0.508 0.508)
					(clearance 0.1016)
				)
				(layer "B.Cu"
					(shape circle)
					(size 0.762 0.762)
					(clearance -0.0254)
				)
			)
		)
	)
	(footprint ""
		(layer "F.Cu")
		(at 108.9406 -80.1624)
		(property "Reference" "U38"
			(at -0.7366 3.49377 0)
			(unlocked yes)
			(layer "F.SilkS")
			(effects
				(font
					(size 0.7874 0.5842)
					(thickness 0.1524)
				)
			)
		)
		(property "Value" ""
			(at 0 0 0)
			(layer "F.Fab")
			(effects
				(font
					(size 1.27 1.27)
				)
			)
		)
		(property "Device Type" "TS3A5018PWR_TSSOP16-G220-10324A"
			(at 0 0.924306 0)
			(unlocked yes)
			(layer "F.Fab")
			(hide yes)
			(effects
				(font
					(size 0.7874 0.5842)
					(thickness 0.000001)
				)
			)
		)
		(property "User Part Number" "PARTNUM*"
			(at 0.254 1.940306 0)
			(unlocked yes)
			(layer "Cmts.User")
			(hide yes)
			(effects
				(font
					(size 0.7874 0.5842)
					(thickness 0.000001)
				)
			)
		)
		(duplicate_pad_numbers_are_jumpers no)
		(fp_line
			(start -4.0767 -2.7559)
			(end 4.0767 -2.7559)
			(stroke
				(width 0.1)
				(type default)
			)
			(layer "F.SilkS")
		)
		(fp_line
			(start -4.0767 2.7559)
			(end -4.0767 -2.7559)
			(stroke
				(width 0.1)
				(type default)
			)
			(layer "F.SilkS")
		)
		(fp_line
			(start 4.0767 -2.7559)
			(end 4.0767 2.7559)
			(stroke
				(width 0.1)
				(type default)
			)
			(layer "F.SilkS")
		)
		(fp_line
			(start 4.0767 2.7559)
			(end -4.0767 2.7559)
			(stroke
				(width 0.1)
				(type default)
			)
			(layer "F.SilkS")
		)
		(fp_poly
			(pts
				(arc
					(start -3.6576 -3.2766)
					(mid -4.4196 -3.2766)
					(end -3.6576 -3.2766)
				)
			)
			(stroke
				(width 0)
				(type default)
			)
			(fill yes)
			(layer "F.SilkS")
		)
		(fp_rect
			(start -4.3307 3.0099)
			(end 4.3307 -3.0099)
			(stroke
				(width 0)
				(type default)
			)
			(fill no)
			(layer "F.CrtYd")
		)
		(fp_line
			(start -2.1971 -2.5019)
			(end 2.1971 -2.5019)
			(stroke
				(width 0.1)
				(type default)
			)
			(layer "F.Fab")
		)
		(fp_line
			(start -2.1971 2.5019)
			(end -2.1971 -2.5019)
			(stroke
				(width 0.1)
				(type default)
			)
			(layer "F.Fab")
		)
		(fp_line
			(start 2.1971 -2.5019)
			(end 2.1971 2.5019)
			(stroke
				(width 0.1)
				(type default)
			)
			(layer "F.Fab")
		)
		(fp_line
			(start 2.1971 2.5019)
			(end -2.1971 2.5019)
			(stroke
				(width 0.1)
				(type default)
			)
			(layer "F.Fab")
		)
		(fp_poly
			(pts
				(arc
					(start -1.114298 -1.942084)
					(mid -1.914398 -1.942084)
					(end -1.114298 -1.942084)
				)
			)
			(stroke
				(width 0)
				(type default)
			)
			(fill yes)
			(layer "F.Fab")
		)
		(fp_text user "8"
			(at -4.572 2.25425 0)
			(unlocked yes)
			(layer "F.SilkS")
			(effects
				(font
					(size 0.635 0.4064)
					(thickness 0.1524)
				)
			)
		)
		(fp_text user "16"
			(at 4.50215 -2.6416 90)
			(unlocked yes)
			(layer "F.SilkS")
			(effects
				(font
					(size 0.635 0.4064)
					(thickness 0.1524)
				)
			)
		)
		(fp_text user "9"
			(at 4.5466 2.38125 0)
			(unlocked yes)
			(layer "F.SilkS")
			(effects
				(font
					(size 0.635 0.4064)
					(thickness 0.1524)
				)
			)
		)
		(fp_text user "8"
			(at -4.572 2.18567 0)
			(unlocked yes)
			(layer "F.Fab")
			(effects
				(font
					(size 0.7874 0.5842)
					(thickness 0.1524)
				)
			)
		)
		(fp_text user "16"
			(at 3.9624 -3.23723 0)
			(unlocked yes)
			(layer "F.Fab")
			(effects
				(font
					(size 0.7874 0.5842)
					(thickness 0.1524)
				)
			)
		)
		(fp_text user "9"
			(at 4.5466 2.31267 0)
			(unlocked yes)
			(layer "F.Fab")
			(effects
				(font
					(size 0.7874 0.5842)
					(thickness 0.1524)
				)
			)
		)
		(pad "1" smd rect
			(at -3.0353 -2.275078 90)
			(size 0.3556 1.5748)
			(layers "F.Cu" "F.Mask" "F.Paste")
			(net "MUX2_SEL")
		)
		(pad "2" smd rect
			(at -3.0353 -1.625092 90)
			(size 0.3556 1.5748)
			(layers "F.Cu" "F.Mask" "F.Paste")
			(net "FPGA_FLASH_CLK")
		)
		(pad "3" smd rect
			(at -3.0353 -0.975106 90)
			(size 0.3556 1.5748)
			(layers "F.Cu" "F.Mask" "F.Paste")
			(net "FT4232_SPI_CLK")
		)
		(pad "4" smd rect
			(at -3.0353 -0.32512 90)
			(size 0.3556 1.5748)
			(layers "F.Cu" "F.Mask" "F.Paste")
			(net "FLASH_CLK")
		)
		(pad "5" smd rect
			(at -3.0353 0.32512 90)
			(size 0.3556 1.5748)
			(layers "F.Cu" "F.Mask" "F.Paste")
			(net "FPGA_FLASH_DQ0_MOSI")
		)
		(pad "6" smd rect
			(at -3.0353 0.975106 90)
			(size 0.3556 1.5748)
			(layers "F.Cu" "F.Mask" "F.Paste")
			(net "FT4232_SPI_MOSI")
		)
		(pad "7" smd rect
			(at -3.0353 1.625092 90)
			(size 0.3556 1.5748)
			(layers "F.Cu" "F.Mask" "F.Paste")
			(net "FLASH_DQ0_MOSI")
		)
		(pad "8" smd rect
			(at -3.0353 2.275078 90)
			(size 0.3556 1.5748)
			(layers "F.Cu" "F.Mask" "F.Paste")
			(net "SG")
		)
		(pad "9" smd rect
			(at 3.0353 2.275078 90)
			(size 0.3556 1.5748)
			(layers "F.Cu" "F.Mask" "F.Paste")
			(net "FLASH_DQ1_MISO")
		)
		(pad "10" smd rect
			(at 3.0353 1.625092 90)
			(size 0.3556 1.5748)
			(layers "F.Cu" "F.Mask" "F.Paste")
			(net "FT4232_SPI_MISO")
		)
		(pad "11" smd rect
			(at 3.0353 0.975106 90)
			(size 0.3556 1.5748)
			(layers "F.Cu" "F.Mask" "F.Paste")
			(net "FPGA_FLASH_DQ1_MISO")
		)
		(pad "12" smd rect
			(at 3.0353 0.32512 90)
			(size 0.3556 1.5748)
			(layers "F.Cu" "F.Mask" "F.Paste")
			(net "FLASH_CS_N")
		)
		(pad "13" smd rect
			(at 3.0353 -0.32512 90)
			(size 0.3556 1.5748)
			(layers "F.Cu" "F.Mask" "F.Paste")
			(net "FT4232_SPI_CS_N")
		)
		(pad "14" smd rect
			(at 3.0353 -0.975106 90)
			(size 0.3556 1.5748)
			(layers "F.Cu" "F.Mask" "F.Paste")
			(net "FPGA_FLASH_CS_N")
		)
		(pad "15" smd rect
			(at 3.0353 -1.625092 90)
			(size 0.3556 1.5748)
			(layers "F.Cu" "F.Mask" "F.Paste")
			(net "UNNAMED_524_RESISTOR_I432_2")
		)
		(pad "16" smd rect
			(at 3.0353 -2.275078 90)
			(size 0.3556 1.5748)
			(layers "F.Cu" "F.Mask" "F.Paste")
			(net "XP3R3V_FPGA")
		)
	)
	(footprint ""
		(layer "F.Cu")
		(at 136.779 -53.086 -90)
		(property "Reference" "C260"
			(at 0 2.75463 90)
			(unlocked yes)
			(layer "F.SilkS")
			(effects
				(font
					(size 0.7874 0.5842)
					(thickness 0.1524)
				)
			)
		)
		(property "Value" "VAL*"
			(at 0.0762 3.134106 270)
			(unlocked yes)
			(layer "F.Fab")
			(hide yes)
			(effects
				(font
					(size 0.7874 0.5842)
					(thickness 0.1524)
				)
			)
		)
		(property "Tolerance" "TOL*"
			(at 0.0762 4.048506 270)
			(unlocked yes)
			(layer "Cmts.User")
			(hide yes)
			(effects
				(font
					(size 0.7874 0.5842)
					(thickness 0.1524)
				)
			)
		)
		(property "User Part Number" "PARTNUM*"
			(at 0.1016 5.013706 270)
			(unlocked yes)
			(layer "Cmts.User")
			(hide yes)
			(effects
				(font
					(size 0.7874 0.5842)
					(thickness 0.1524)
				)
			)
		)
		(property "Device Type" "CAPACITOR-G107-0F106-EM,10UF,2A"
			(at 0.0508 2.194306 270)
			(unlocked yes)
			(layer "F.Fab")
			(hide yes)
			(effects
				(font
					(size 0.7874 0.5842)
					(thickness 0.1524)
				)
			)
		)
		(duplicate_pad_numbers_are_jumpers no)
		(fp_line
			(start -1.5748 0.9398)
			(end 1.5748 0.9398)
			(stroke
				(width 0.1)
				(type default)
			)
			(layer "F.SilkS")
		)
		(fp_line
			(start 1.5748 0.9398)
			(end 1.5748 -0.9398)
			(stroke
				(width 0.1)
				(type default)
			)
			(layer "F.SilkS")
		)
		(fp_line
			(start -1.5748 -0.9398)
			(end -1.5748 0.9398)
			(stroke
				(width 0.1)
				(type default)
			)
			(layer "F.SilkS")
		)
		(fp_line
			(start 1.5748 -0.9398)
			(end -1.5748 -0.9398)
			(stroke
				(width 0.1)
				(type default)
			)
			(layer "F.SilkS")
		)
		(fp_rect
			(start 1.5748 0.9398)
			(end -1.5748 -0.9398)
			(stroke
				(width 0)
				(type default)
			)
			(fill no)
			(layer "F.CrtYd")
		)
		(fp_line
			(start -1.016 0.635)
			(end 1.016 0.635)
			(stroke
				(width 0.1)
				(type default)
			)
			(layer "F.Fab")
		)
		(fp_line
			(start 1.016 0.635)
			(end 1.016 -0.635)
			(stroke
				(width 0.1)
				(type default)
			)
			(layer "F.Fab")
		)
		(fp_line
			(start -1.016 -0.635)
			(end -1.016 0.635)
			(stroke
				(width 0.1)
				(type default)
			)
			(layer "F.Fab")
		)
		(fp_line
			(start 1.016 -0.635)
			(end -1.016 -0.635)
			(stroke
				(width 0.1)
				(type default)
			)
			(layer "F.Fab")
		)
		(pad "1" smd rect
			(at -0.8382 0 270)
			(size 0.9652 1.3716)
			(layers "F.Cu" "F.Mask" "F.Paste")
			(net "VIN_XP1R0V")
		)
		(pad "2" smd rect
			(at 0.8382 0 270)
			(size 0.9652 1.3716)
			(layers "F.Cu" "F.Mask" "F.Paste")
			(net "SG")
		)
		(zone
			(layer "F.Cu")
			(hatch none 0.5)
			(connect_pads
				(clearance 0)
			)
			(min_thickness 0.25)
			(keepout
				(tracks allowed)
				(vias not_allowed)
				(pads allowed)
				(copperpour not_allowed)
				(footprints allowed)
			)
			(placement
				(enabled no)
				(sheetname "")
			)
			(fill
				(thermal_gap 0.5)
				(thermal_bridge_width 0.5)
				(island_removal_mode 0)
			)
			(polygon
				(pts
					(xy 136.144 -52.8574) (xy 137.414 -52.8574) (xy 137.414 -53.3146) (xy 136.144 -53.3146)
				)
			)
		)
	)
	(footprint ""
		(layer "F.Cu")
		(at 127.762 -39.37 -90)
		(property "Reference" "TP134"
			(at 0.8128 -1.04775 90)
			(unlocked yes)
			(layer "F.SilkS")
			(effects
				(font
					(size 0.635 0.4064)
					(thickness 0.1524)
				)
				(justify left)
			)
		)
		(property "Value" ""
			(at 0 0 270)
			(layer "F.Fab")
			(effects
				(font
					(size 1.27 1.27)
				)
			)
		)
		(property "Device Type" "TP_PIONT-TP010CT020B030_PTH-TPA"
			(at -1.341882 0.996696 270)
			(unlocked yes)
			(layer "F.Fab")
			(hide yes)
			(effects
				(font
					(size 0.7874 0.5842)
					(thickness 0.1524)
				)
				(justify left)
			)
		)
		(duplicate_pad_numbers_are_jumpers no)
		(fp_poly
			(pts
				(arc
					(start 0 -0.889)
					(mid 0 0.889)
					(end 0 -0.889)
				)
			)
			(stroke
				(width 0)
				(type default)
			)
			(fill no)
			(layer "B.CrtYd")
		)
		(fp_poly
			(pts
				(arc
					(start 0 -0.889)
					(mid 0 0.889)
					(end 0 -0.889)
				)
			)
			(stroke
				(width 0)
				(type default)
			)
			(fill no)
			(layer "F.CrtYd")
		)
		(pad "1" thru_hole circle
			(at 0 0 270)
			(size 0.508 0.508)
			(drill 0.254)
			(layers "*.Cu" "*.Mask")
			(remove_unused_layers no)
			(net "IO_L21P_34")
			(clearance 0.1016)
			(padstack
				(mode front_inner_back)
				(layer "Inner"
					(shape circle)
					(size 0.508 0.508)
					(clearance 0.1016)
				)
				(layer "B.Cu"
					(shape circle)
					(size 0.762 0.762)
					(clearance -0.0254)
				)
			)
		)
	)
)
